(kicad_pcb
	(version 20260206)
	(generator "pcbnew")
	(generator_version "10.0")
	(general
		(thickness 1.6)
		(legacy_teardrops no)
	)
	(paper "A4")
	(title_block
		(title "01162023_DA0F0TEBIF0_F0T_Expander_BD_F_brd_V02_OCP.brd")
		(comment 1 "Grand Teton / footprints 3653-3658 of 9728")
	)
	(layers
		(0 "F.Cu" signal "TOP")
		(4 "In1.Cu" signal "GND")
		(6 "In2.Cu" signal "VCC")
		(8 "In3.Cu" signal "VCC1")
		(10 "In4.Cu" signal "GND1")
		(12 "In5.Cu" signal "IN1")
		(14 "In6.Cu" signal "GND2")
		(16 "In7.Cu" signal "IN2")
		(18 "In8.Cu" signal "GND3")
		(20 "In9.Cu" signal "IN3")
		(22 "In10.Cu" signal "GND4")
		(24 "In11.Cu" signal "IN4")
		(26 "In12.Cu" signal "GND5")
		(28 "In13.Cu" signal "IN5")
		(30 "In14.Cu" signal "GND6")
		(32 "In15.Cu" signal "IN6")
		(34 "In16.Cu" signal "GND7")
		(2 "B.Cu" signal "BOTTOM")
		(9 "F.Adhes" user "F.Adhesive")
		(11 "B.Adhes" user "B.Adhesive")
		(13 "F.Paste" user "Package Geometry/Pastemask Top")
		(15 "B.Paste" user "Package Geometry/Pastemask Bottom")
		(5 "F.SilkS" user "Ref Des/Silkscreen Top")
		(7 "B.SilkS" user "Ref Des/Silkscreen Bottom")
		(1 "F.Mask" user "Board Geometry/Soldermask Top")
		(3 "B.Mask" user "Board Geometry/Soldermask Bottom")
		(17 "Dwgs.User" user "User.Drawings")
		(19 "Cmts.User" user "User.Comments")
		(21 "Eco1.User" user "User.Eco1")
		(23 "Eco2.User" user "User.Eco2")
		(25 "Edge.Cuts" user "Board Geometry/Outline")
		(27 "Margin" user)
		(31 "F.CrtYd" user "Package Geometry/Place Bound Top")
		(29 "B.CrtYd" user "Package Geometry/Place Bound Bottom")
		(35 "F.Fab" user "Ref Des/Assembly Top")
		(33 "B.Fab" user "Ref Des/Assembly Bottom")
	)
	(footprint ""
		(layer "F.Cu")
		(at 127.658114 -256.226564 180)
		(property "Reference" "PR85"
			(at 0 0 180)
			(layer "F.SilkS")
			(hide yes)
			(effects
				(font
					(size 1.27 1.27)
				)
			)
		)
		(property "Value" ""
			(at 0 0 180)
			(layer "F.Fab")
			(effects
				(font
					(size 1.27 1.27)
				)
			)
		)
		(duplicate_pad_numbers_are_jumpers no)
		(fp_line
			(start 0.7874 0.4064)
			(end -0.7874 0.4064)
			(stroke
				(width 0.1524)
				(type default)
			)
			(layer "F.SilkS")
		)
		(fp_line
			(start 0.7874 -0.4064)
			(end 0.7874 0.4064)
			(stroke
				(width 0.1524)
				(type default)
			)
			(layer "F.SilkS")
		)
		(fp_line
			(start -0.7874 0.4064)
			(end -0.7874 -0.4064)
			(stroke
				(width 0.1524)
				(type default)
			)
			(layer "F.SilkS")
		)
		(fp_line
			(start -0.7874 -0.4064)
			(end 0.7874 -0.4064)
			(stroke
				(width 0.1524)
				(type default)
			)
			(layer "F.SilkS")
		)
		(fp_line
			(start 0.67945 0.3048)
			(end 0.120396 0.3048)
			(stroke
				(width 0.1)
				(type default)
			)
			(layer "F.Fab")
		)
		(fp_line
			(start 0.67945 -0.3048)
			(end 0.67945 0.3048)
			(stroke
				(width 0.1)
				(type default)
			)
			(layer "F.Fab")
		)
		(fp_line
			(start 0.12065 -0.2794)
			(end 0.12065 -0.3048)
			(stroke
				(width 0.1)
				(type default)
			)
			(layer "F.Fab")
		)
		(fp_line
			(start 0.12065 -0.3048)
			(end 0.67945 -0.3048)
			(stroke
				(width 0.1)
				(type default)
			)
			(layer "F.Fab")
		)
		(fp_line
			(start 0.120396 0.3048)
			(end 0.120396 0.2794)
			(stroke
				(width 0.1)
				(type default)
			)
			(layer "F.Fab")
		)
		(fp_line
			(start 0.120396 0.2794)
			(end -0.12065 0.2794)
			(stroke
				(width 0.1)
				(type default)
			)
			(layer "F.Fab")
		)
		(fp_line
			(start -0.12065 0.3048)
			(end -0.67945 0.3048)
			(stroke
				(width 0.1)
				(type default)
			)
			(layer "F.Fab")
		)
		(fp_line
			(start -0.12065 0.2794)
			(end -0.12065 0.3048)
			(stroke
				(width 0.1)
				(type default)
			)
			(layer "F.Fab")
		)
		(fp_line
			(start -0.12065 -0.2794)
			(end 0.12065 -0.2794)
			(stroke
				(width 0.1)
				(type default)
			)
			(layer "F.Fab")
		)
		(fp_line
			(start -0.12065 -0.305054)
			(end -0.12065 -0.2794)
			(stroke
				(width 0.1)
				(type default)
			)
			(layer "F.Fab")
		)
		(fp_line
			(start -0.67945 0.3048)
			(end -0.67945 -0.305054)
			(stroke
				(width 0.1)
				(type default)
			)
			(layer "F.Fab")
		)
		(fp_line
			(start -0.67945 -0.305054)
			(end -0.12065 -0.305054)
			(stroke
				(width 0.1)
				(type default)
			)
			(layer "F.Fab")
		)
		(pad "1" smd circle
			(at -0.40005 0 180)
			(size 0 0)
			(layers "F.Cu" "F.Mask" "F.Paste")
			(net "P3V3_AUX")
		)
		(pad "2" smd circle
			(at 0.40005 0 180)
			(size 0 0)
			(layers "F.Cu" "F.Mask" "F.Paste")
			(net "P0V8_PEX0_VRHOT_R")
		)
	)
	(footprint ""
		(layer "F.Cu")
		(at 314.3504 -80.581246 90)
		(property "Reference" "U37"
			(at -0.571246 2.38887 90)
			(unlocked yes)
			(layer "F.SilkS")
			(effects
				(font
					(size 0.7874 0.5842)
					(thickness 0.1524)
				)
			)
		)
		(property "Value" ""
			(at 0 0 90)
			(layer "F.Fab")
			(effects
				(font
					(size 1.27 1.27)
				)
			)
		)
		(duplicate_pad_numbers_are_jumpers no)
		(fp_line
			(start 1.905 -1.651)
			(end 1.905 1.651)
			(stroke
				(width 0.1524)
				(type default)
			)
			(layer "F.SilkS")
		)
		(fp_line
			(start -1.905 -1.651)
			(end 1.905 -1.651)
			(stroke
				(width 0.1524)
				(type default)
			)
			(layer "F.SilkS")
		)
		(fp_line
			(start 1.905 1.651)
			(end -1.905 1.651)
			(stroke
				(width 0.1524)
				(type default)
			)
			(layer "F.SilkS")
		)
		(fp_line
			(start -1.905 1.651)
			(end -1.905 -1.651)
			(stroke
				(width 0.1524)
				(type default)
			)
			(layer "F.SilkS")
		)
		(fp_line
			(start 0.6985 -1.524)
			(end 0.6985 -0.219964)
			(stroke
				(width 0.1)
				(type default)
			)
			(layer "F.Fab")
		)
		(fp_line
			(start -0.649986 -1.524)
			(end 0.6985 -1.524)
			(stroke
				(width 0.1)
				(type default)
			)
			(layer "F.Fab")
		)
		(fp_line
			(start -0.649986 -1.169924)
			(end -0.649986 -1.524)
			(stroke
				(width 0.1)
				(type default)
			)
			(layer "F.Fab")
		)
		(fp_line
			(start -1.249934 -1.169924)
			(end -0.649986 -1.169924)
			(stroke
				(width 0.1)
				(type default)
			)
			(layer "F.Fab")
		)
		(fp_line
			(start -0.6985 -0.729996)
			(end -1.249934 -0.729996)
			(stroke
				(width 0.1)
				(type default)
			)
			(layer "F.Fab")
		)
		(fp_line
			(start -1.249934 -0.729996)
			(end -1.249934 -1.169924)
			(stroke
				(width 0.1)
				(type default)
			)
			(layer "F.Fab")
		)
		(fp_line
			(start 1.249934 -0.219964)
			(end 1.249934 0.219964)
			(stroke
				(width 0.1)
				(type default)
			)
			(layer "F.Fab")
		)
		(fp_line
			(start 0.6985 -0.219964)
			(end 1.249934 -0.219964)
			(stroke
				(width 0.1)
				(type default)
			)
			(layer "F.Fab")
		)
		(fp_line
			(start 1.249934 0.219964)
			(end 0.6985 0.219964)
			(stroke
				(width 0.1)
				(type default)
			)
			(layer "F.Fab")
		)
		(fp_line
			(start 0.6985 0.219964)
			(end 0.6985 1.524)
			(stroke
				(width 0.1)
				(type default)
			)
			(layer "F.Fab")
		)
		(fp_line
			(start -0.6985 0.729996)
			(end -0.6985 -0.729996)
			(stroke
				(width 0.1)
				(type default)
			)
			(layer "F.Fab")
		)
		(fp_line
			(start -1.249934 0.729996)
			(end -0.6985 0.729996)
			(stroke
				(width 0.1)
				(type default)
			)
			(layer "F.Fab")
		)
		(fp_line
			(start -0.649986 1.169924)
			(end -1.249934 1.169924)
			(stroke
				(width 0.1)
				(type default)
			)
			(layer "F.Fab")
		)
		(fp_line
			(start -1.249934 1.169924)
			(end -1.249934 0.729996)
			(stroke
				(width 0.1)
				(type default)
			)
			(layer "F.Fab")
		)
		(fp_line
			(start 0.6985 1.524)
			(end -0.649986 1.524)
			(stroke
				(width 0.1)
				(type default)
			)
			(layer "F.Fab")
		)
		(fp_line
			(start -0.649986 1.524)
			(end -0.649986 1.169924)
			(stroke
				(width 0.1)
				(type default)
			)
			(layer "F.Fab")
		)
		(pad "1" smd rect
			(at -1.1176 -1.016)
			(size 1.016 1.27)
			(layers "F.Cu" "F.Mask" "F.Paste")
			(net "HP_NIC5_PWRGD")
		)
		(pad "2" smd rect
			(at -1.1176 1.016)
			(size 1.016 1.27)
			(layers "F.Cu" "F.Mask" "F.Paste")
			(net "P3V3_NIC5")
		)
		(pad "3" smd rect
			(at 1.1176 0)
			(size 1.016 1.27)
			(layers "F.Cu" "F.Mask" "F.Paste")
			(net "GND")
		)
	)
	(footprint ""
		(layer "F.Cu")
		(at 345.632278 -280.44902 -90)
		(property "Reference" "PR153"
			(at 0 0 270)
			(layer "F.SilkS")
			(hide yes)
			(effects
				(font
					(size 1.27 1.27)
				)
			)
		)
		(property "Value" ""
			(at 0 0 270)
			(layer "F.Fab")
			(effects
				(font
					(size 1.27 1.27)
				)
			)
		)
		(duplicate_pad_numbers_are_jumpers no)
		(fp_line
			(start -0.7874 0.4064)
			(end -0.7874 -0.4064)
			(stroke
				(width 0.1524)
				(type default)
			)
			(layer "F.SilkS")
		)
		(fp_line
			(start 0.7874 0.4064)
			(end -0.7874 0.4064)
			(stroke
				(width 0.1524)
				(type default)
			)
			(layer "F.SilkS")
		)
		(fp_line
			(start -0.7874 -0.4064)
			(end 0.7874 -0.4064)
			(stroke
				(width 0.1524)
				(type default)
			)
			(layer "F.SilkS")
		)
		(fp_line
			(start 0.7874 -0.4064)
			(end 0.7874 0.4064)
			(stroke
				(width 0.1524)
				(type default)
			)
			(layer "F.SilkS")
		)
		(fp_line
			(start -0.67945 0.3048)
			(end -0.67945 -0.305054)
			(stroke
				(width 0.1)
				(type default)
			)
			(layer "F.Fab")
		)
		(fp_line
			(start -0.12065 0.3048)
			(end -0.67945 0.3048)
			(stroke
				(width 0.1)
				(type default)
			)
			(layer "F.Fab")
		)
		(fp_line
			(start 0.120396 0.3048)
			(end 0.120396 0.2794)
			(stroke
				(width 0.1)
				(type default)
			)
			(layer "F.Fab")
		)
		(fp_line
			(start 0.67945 0.3048)
			(end 0.120396 0.3048)
			(stroke
				(width 0.1)
				(type default)
			)
			(layer "F.Fab")
		)
		(fp_line
			(start -0.12065 0.2794)
			(end -0.12065 0.3048)
			(stroke
				(width 0.1)
				(type default)
			)
			(layer "F.Fab")
		)
		(fp_line
			(start 0.120396 0.2794)
			(end -0.12065 0.2794)
			(stroke
				(width 0.1)
				(type default)
			)
			(layer "F.Fab")
		)
		(fp_line
			(start -0.12065 -0.2794)
			(end 0.12065 -0.2794)
			(stroke
				(width 0.1)
				(type default)
			)
			(layer "F.Fab")
		)
		(fp_line
			(start 0.12065 -0.2794)
			(end 0.12065 -0.3048)
			(stroke
				(width 0.1)
				(type default)
			)
			(layer "F.Fab")
		)
		(fp_line
			(start 0.12065 -0.3048)
			(end 0.67945 -0.3048)
			(stroke
				(width 0.1)
				(type default)
			)
			(layer "F.Fab")
		)
		(fp_line
			(start 0.67945 -0.3048)
			(end 0.67945 0.3048)
			(stroke
				(width 0.1)
				(type default)
			)
			(layer "F.Fab")
		)
		(fp_line
			(start -0.67945 -0.305054)
			(end -0.12065 -0.305054)
			(stroke
				(width 0.1)
				(type default)
			)
			(layer "F.Fab")
		)
		(fp_line
			(start -0.12065 -0.305054)
			(end -0.12065 -0.2794)
			(stroke
				(width 0.1)
				(type default)
			)
			(layer "F.Fab")
		)
		(pad "1" smd circle
			(at -0.40005 0 270)
			(size 0 0)
			(layers "F.Cu" "F.Mask" "F.Paste")
			(net "SW_P0V8_PEX2_BOOT2")
		)
		(pad "2" smd circle
			(at 0.40005 0 270)
			(size 0 0)
			(layers "F.Cu" "F.Mask" "F.Paste")
			(net "SW_P0V8_PEX2_BOOT2_R")
		)
	)
	(footprint ""
		(layer "F.Cu")
		(at 438.164732 -356.244906 90)
		(property "Reference" "C2468"
			(at 0 0 90)
			(layer "F.SilkS")
			(hide yes)
			(effects
				(font
					(size 1.27 1.27)
				)
			)
		)
		(property "Value" ""
			(at 0 0 90)
			(layer "F.Fab")
			(effects
				(font
					(size 1.27 1.27)
				)
			)
		)
		(duplicate_pad_numbers_are_jumpers no)
		(fp_line
			(start 0.299974 -0.150114)
			(end 0.299974 0.150114)
			(stroke
				(width 0.1)
				(type default)
			)
			(layer "F.Fab")
		)
		(fp_line
			(start -0.299974 -0.150114)
			(end 0.299974 -0.150114)
			(stroke
				(width 0.1)
				(type default)
			)
			(layer "F.Fab")
		)
		(fp_line
			(start 0.299974 0.150114)
			(end -0.299974 0.150114)
			(stroke
				(width 0.1)
				(type default)
			)
			(layer "F.Fab")
		)
		(fp_line
			(start -0.299974 0.150114)
			(end -0.299974 -0.150114)
			(stroke
				(width 0.1)
				(type default)
			)
			(layer "F.Fab")
		)
		(pad "1" smd rect
			(at -0.2667 0 90)
			(size 0.3048 0.381)
			(layers "F.Cu" "F.Mask" "F.Paste")
			(net "P5E_PEX3_STN4_TX_DN<65>")
		)
		(pad "2" smd rect
			(at 0.2667 0 90)
			(size 0.3048 0.381)
			(layers "F.Cu" "F.Mask" "F.Paste")
			(net "P5E_PEX3_STN4_TX_C_DN<65>")
		)
	)
	(footprint ""
		(layer "F.Cu")
		(at 206.128366 -300.64202 -90)
		(property "Reference" "R3925"
			(at 0 0 270)
			(layer "F.SilkS")
			(hide yes)
			(effects
				(font
					(size 1.27 1.27)
				)
			)
		)
		(property "Value" ""
			(at 0 0 270)
			(layer "F.Fab")
			(effects
				(font
					(size 1.27 1.27)
				)
			)
		)
		(duplicate_pad_numbers_are_jumpers no)
		(fp_line
			(start -0.7874 0.4064)
			(end -0.7874 -0.4064)
			(stroke
				(width 0.1524)
				(type default)
			)
			(layer "F.SilkS")
		)
		(fp_line
			(start 0.7874 0.4064)
			(end -0.7874 0.4064)
			(stroke
				(width 0.1524)
				(type default)
			)
			(layer "F.SilkS")
		)
		(fp_line
			(start -0.7874 -0.4064)
			(end 0.7874 -0.4064)
			(stroke
				(width 0.1524)
				(type default)
			)
			(layer "F.SilkS")
		)
		(fp_line
			(start 0.7874 -0.4064)
			(end 0.7874 0.4064)
			(stroke
				(width 0.1524)
				(type default)
			)
			(layer "F.SilkS")
		)
		(fp_line
			(start -0.67945 0.3048)
			(end -0.67945 -0.305054)
			(stroke
				(width 0.1)
				(type default)
			)
			(layer "F.Fab")
		)
		(fp_line
			(start -0.12065 0.3048)
			(end -0.67945 0.3048)
			(stroke
				(width 0.1)
				(type default)
			)
			(layer "F.Fab")
		)
		(fp_line
			(start 0.120396 0.3048)
			(end 0.120396 0.2794)
			(stroke
				(width 0.1)
				(type default)
			)
			(layer "F.Fab")
		)
		(fp_line
			(start 0.67945 0.3048)
			(end 0.120396 0.3048)
			(stroke
				(width 0.1)
				(type default)
			)
			(layer "F.Fab")
		)
		(fp_line
			(start -0.12065 0.2794)
			(end -0.12065 0.3048)
			(stroke
				(width 0.1)
				(type default)
			)
			(layer "F.Fab")
		)
		(fp_line
			(start 0.120396 0.2794)
			(end -0.12065 0.2794)
			(stroke
				(width 0.1)
				(type default)
			)
			(layer "F.Fab")
		)
		(fp_line
			(start -0.12065 -0.2794)
			(end 0.12065 -0.2794)
			(stroke
				(width 0.1)
				(type default)
			)
			(layer "F.Fab")
		)
		(fp_line
			(start 0.12065 -0.2794)
			(end 0.12065 -0.3048)
			(stroke
				(width 0.1)
				(type default)
			)
			(layer "F.Fab")
		)
		(fp_line
			(start 0.12065 -0.3048)
			(end 0.67945 -0.3048)
			(stroke
				(width 0.1)
				(type default)
			)
			(layer "F.Fab")
		)
		(fp_line
			(start 0.67945 -0.3048)
			(end 0.67945 0.3048)
			(stroke
				(width 0.1)
				(type default)
			)
			(layer "F.Fab")
		)
		(fp_line
			(start -0.67945 -0.305054)
			(end -0.12065 -0.305054)
			(stroke
				(width 0.1)
				(type default)
			)
			(layer "F.Fab")
		)
		(fp_line
			(start -0.12065 -0.305054)
			(end -0.12065 -0.2794)
			(stroke
				(width 0.1)
				(type default)
			)
			(layer "F.Fab")
		)
		(pad "1" smd circle
			(at -0.40005 0 270)
			(size 0 0)
			(layers "F.Cu" "F.Mask" "F.Paste")
			(net "I2C0_PEX1_SDA")
		)
		(pad "2" smd circle
			(at 0.40005 0 270)
			(size 0 0)
			(layers "F.Cu" "F.Mask" "F.Paste")
			(net "I2C_PEX1_HOST_SDA")
		)
	)
	(footprint ""
		(layer "F.Cu")
		(at 21.74621 -166.87546 180)
		(property "Reference" "PL1"
			(at 0.10541 -1.31953 0)
			(unlocked yes)
			(layer "F.SilkS")
			(effects
				(font
					(size 0.7874 0.5842)
					(thickness 0.1524)
				)
			)
		)
		(property "Value" ""
			(at 0 0 180)
			(layer "F.Fab")
			(effects
				(font
					(size 1.27 1.27)
				)
			)
		)
		(duplicate_pad_numbers_are_jumpers no)
		(fp_line
			(start 1.27 0.5842)
			(end 1.27 -0.5842)
			(stroke
				(width 0.1524)
				(type default)
			)
			(layer "F.SilkS")
		)
		(fp_line
			(start 1.27 0.5842)
			(end -1.27 0.5842)
			(stroke
				(width 0.1524)
				(type default)
			)
			(layer "F.SilkS")
		)
		(fp_line
			(start -1.27 0.5842)
			(end -1.27 -0.5842)
			(stroke
				(width 0.1524)
				(type default)
			)
			(layer "F.SilkS")
		)
		(fp_line
			(start -1.27 -0.5588)
			(end -1.27 -0.5842)
			(stroke
				(width 0.1524)
				(type default)
			)
			(layer "F.SilkS")
		)
		(fp_line
			(start -1.27 -0.5842)
			(end 1.27 -0.5842)
			(stroke
				(width 0.1524)
				(type default)
			)
			(layer "F.SilkS")
		)
		(fp_line
			(start 1.1938 0.4064)
			(end 0.9144 0.4064)
			(stroke
				(width 0.1)
				(type default)
			)
			(layer "F.Fab")
		)
		(fp_line
			(start 1.1938 -0.406654)
			(end 1.1938 0.4064)
			(stroke
				(width 0.1)
				(type default)
			)
			(layer "F.Fab")
		)
		(fp_line
			(start 0.9144 0.508)
			(end -0.9144 0.508)
			(stroke
				(width 0.1)
				(type default)
			)
			(layer "F.Fab")
		)
		(fp_line
			(start 0.9144 0.4064)
			(end 0.9144 0.508)
			(stroke
				(width 0.1)
				(type default)
			)
			(layer "F.Fab")
		)
		(fp_line
			(start 0.9144 -0.406654)
			(end 1.1938 -0.406654)
			(stroke
				(width 0.1)
				(type default)
			)
			(layer "F.Fab")
		)
		(fp_line
			(start 0.9144 -0.508)
			(end 0.9144 -0.406654)
			(stroke
				(width 0.1)
				(type default)
			)
			(layer "F.Fab")
		)
		(fp_line
			(start -0.9144 0.508)
			(end -0.9144 0.406654)
			(stroke
				(width 0.1)
				(type default)
			)
			(layer "F.Fab")
		)
		(fp_line
			(start -0.9144 0.406654)
			(end -1.194308 0.406654)
			(stroke
				(width 0.1)
				(type default)
			)
			(layer "F.Fab")
		)
		(fp_line
			(start -0.9144 -0.406654)
			(end -0.9144 -0.508)
			(stroke
				(width 0.1)
				(type default)
			)
			(layer "F.Fab")
		)
		(fp_line
			(start -0.9144 -0.508)
			(end 0.9144 -0.508)
			(stroke
				(width 0.1)
				(type default)
			)
			(layer "F.Fab")
		)
		(fp_line
			(start -1.194308 0.406654)
			(end -1.194308 -0.406654)
			(stroke
				(width 0.1)
				(type default)
			)
			(layer "F.Fab")
		)
		(fp_line
			(start -1.194308 -0.406654)
			(end -0.9144 -0.406654)
			(stroke
				(width 0.1)
				(type default)
			)
			(layer "F.Fab")
		)
		(pad "1" smd rect
			(at -0.7366 0 90)
			(size 0.7112 0.8128)
			(layers "F.Cu" "F.Mask" "F.Paste")
			(net "P12V_AUX")
		)
		(pad "2" smd rect
			(at 0.7366 0 90)
			(size 0.7112 0.8128)
			(layers "F.Cu" "F.Mask" "F.Paste")
			(net "SW_P12V_P5V_AUX_FLT")
		)
	)
)
